(kicad_pcb
	(version 20260206)
	(generator "pcbnew")
	(generator_version "10.0")
	(general
		(thickness 1.21888)
		(legacy_teardrops no)
	)
	(paper "A4")
	(title_block
		(title "timecard-v9 — TimeCard-DC-V9_EXP.PcbDoc")
		(comment 1 "Time Appliance Project (Time Card) / footprints 209-217 of 402")
	)
	(layers
		(0 "F.Cu" signal "TOP")
		(4 "In1.Cu" signal "SGND")
		(6 "In2.Cu" signal "IN1")
		(8 "In3.Cu" signal "IN2")
		(10 "In4.Cu" signal "SGND1")
		(2 "B.Cu" signal "BOTTOM")
		(9 "F.Adhes" user "F.Adhesive")
		(11 "B.Adhes" user "B.Adhesive")
		(13 "F.Paste" user "Top Paste")
		(15 "B.Paste" user "Bottom Paste")
		(5 "F.SilkS" user "Top Overlay")
		(7 "B.SilkS" user "Bottom Overlay")
		(1 "F.Mask" user "Top Solder")
		(3 "B.Mask" user "Bottom Solder")
		(17 "Dwgs.User" user "User.Drawings")
		(19 "Cmts.User" user "User.Comments")
		(21 "Eco1.User" user "User.Eco1")
		(23 "Eco2.User" user "User.Eco2")
		(25 "Edge.Cuts" user)
		(27 "Margin" user)
		(31 "F.CrtYd" user "Top Courtyard")
		(29 "B.CrtYd" user "Bottom Courtyard")
		(35 "F.Fab" user "Top Component Center")
		(33 "B.Fab" user "Bottom Component Center")
	)
	(footprint "Vault:RESC1005X40X25NL05T05"
		(layer "F.Cu")
		(at 108.4216 58.1162 180)
		(property "Reference" "R157"
			(at 3.05685 -0.473971 0)
			(unlocked yes)
			(layer "F.SilkS")
			(effects
				(font
					(size 0.762 0.762)
					(thickness 0.2032)
				)
			)
		)
		(property "Value" "DNI_27_1%_0402"
			(at -2.732271 10.270975 90)
			(unlocked yes)
			(layer "F.SilkS")
			(hide yes)
			(effects
				(font
					(size 0.762 0.762)
					(thickness 0.2032)
				)
			)
		)
		(sheetname "11-M2_RCB_MUX")
		(sheetfile "11-M2_RCB_MUX.kicad_sch")
		(duplicate_pad_numbers_are_jumpers no)
		(pad "1" smd rect
			(at -0.45 0 270)
			(size 0.55 0.55)
			(layers "F.Cu" "F.Mask" "F.Paste")
			(net "RCB_GPS1_RX")
		)
		(pad "2" smd rect
			(at 0.45 0 270)
			(size 0.55 0.55)
			(layers "F.Cu" "F.Mask" "F.Paste")
			(net "GPS1_RX")
		)
	)
	(footprint "Vault:FP-0402-L_1_0_1-W_0_5_0_1-IPC_C"
		(layer "F.Cu")
		(at 74.6216 115.5162 180)
		(property "Reference" "C29"
			(at 2.1714 -0.326931 0)
			(unlocked yes)
			(layer "F.SilkS")
			(effects
				(font
					(size 0.762 0.762)
					(thickness 0.2286)
				)
			)
		)
		(property "Value" "0.1uF_25V_0402"
			(at 2.069035 2.567191 180)
			(unlocked yes)
			(layer "F.SilkS")
			(hide yes)
			(effects
				(font
					(size 0.762 0.762)
					(thickness 0.2286)
				)
			)
		)
		(sheetname "01-USER_IO")
		(sheetfile "01-USER_IO.kicad_sch")
		(duplicate_pad_numbers_are_jumpers no)
		(fp_line
			(start 0.65607 0.7)
			(end -0.65607 0.7)
			(stroke
				(width 0.2)
				(type solid)
			)
			(layer "F.SilkS")
		)
		(fp_line
			(start 0.65607 -0.7)
			(end -0.65607 -0.7)
			(stroke
				(width 0.2)
				(type solid)
			)
			(layer "F.SilkS")
		)
		(fp_line
			(start 0.75607 0.4)
			(end -0.75607 0.4)
			(stroke
				(width 0.2)
				(type solid)
			)
			(layer "F.CrtYd")
		)
		(fp_line
			(start 0.75607 -0.4)
			(end 0.75607 0.4)
			(stroke
				(width 0.2)
				(type solid)
			)
			(layer "F.CrtYd")
		)
		(fp_line
			(start 0.75607 -0.4)
			(end -0.75607 -0.4)
			(stroke
				(width 0.2)
				(type solid)
			)
			(layer "F.CrtYd")
		)
		(fp_line
			(start -0.75607 -0.4)
			(end -0.75607 0.4)
			(stroke
				(width 0.2)
				(type solid)
			)
			(layer "F.CrtYd")
		)
		(fp_line
			(start 0.75607 0.4)
			(end -0.75607 0.4)
			(stroke
				(width 0.2)
				(type solid)
			)
			(layer "F.Fab")
		)
		(fp_line
			(start 0.75607 -0.4)
			(end 0.75607 0.4)
			(stroke
				(width 0.2)
				(type solid)
			)
			(layer "F.Fab")
		)
		(fp_line
			(start 0.75607 -0.4)
			(end -0.75607 -0.4)
			(stroke
				(width 0.2)
				(type solid)
			)
			(layer "F.Fab")
		)
		(fp_line
			(start 0.5 0)
			(end -0.5 0)
			(stroke
				(width 0.1)
				(type solid)
			)
			(layer "F.Fab")
		)
		(fp_line
			(start 0 -0.5)
			(end 0 0.5)
			(stroke
				(width 0.1)
				(type solid)
			)
			(layer "F.Fab")
		)
		(fp_line
			(start -0.75607 -0.4)
			(end -0.75607 0.4)
			(stroke
				(width 0.2)
				(type solid)
			)
			(layer "F.Fab")
		)
		(fp_text user "${REFERENCE}"
			(at -0.00001 0.09601 180)
			(unlocked yes)
			(layer "F.Fab")
			(effects
				(font
					(face "Arial")
					(size 0.63 0.63)
					(thickness 0.1)
				)
				(justify left bottom)
			)
		)
		(pad "1" smd rect
			(at -0.36554 0 180)
			(size 0.58106 0.51213)
			(layers "F.Cu" "F.Mask" "F.Paste")
			(net "+3.3V")
			(solder_mask_margin 0)
			(solder_paste_margin 0)
		)
		(pad "2" smd rect
			(at 0.36554 0 180)
			(size 0.58106 0.51213)
			(layers "F.Cu" "F.Mask" "F.Paste")
			(net "GND")
			(solder_mask_margin 0)
			(solder_paste_margin 0)
		)
	)
	(footprint "Vault:RESC1005X40X25NL05T05"
		(layer "F.Cu")
		(at 155.6216 131.4662 90)
		(property "Reference" "R92"
			(at -1.8214 -0.073069 90)
			(unlocked yes)
			(layer "F.SilkS")
			(effects
				(font
					(size 0.762 0.762)
					(thickness 0.2286)
				)
			)
		)
		(property "Value" "27_1%_0402"
			(at -2.732271 7.37632 0)
			(unlocked yes)
			(layer "F.SilkS")
			(hide yes)
			(effects
				(font
					(size 0.762 0.762)
					(thickness 0.2286)
				)
			)
		)
		(sheetname "09-USBUart_PPSMUX_UARTMUX")
		(sheetfile "09-USBUart_PPSMUX_UARTMUX.kicad_sch")
		(duplicate_pad_numbers_are_jumpers no)
		(pad "1" smd rect
			(at -0.45 0 180)
			(size 0.55 0.55)
			(layers "F.Cu" "F.Mask" "F.Paste")
			(net "FTDI_TX")
		)
		(pad "2" smd rect
			(at 0.45 0 180)
			(size 0.55 0.55)
			(layers "F.Cu" "F.Mask" "F.Paste")
			(net "NetR92_2")
		)
	)
	(footprint "Vault:RESC1005X40X25LL05T10"
		(layer "F.Cu")
		(at 117.6216 77.4162)
		(property "Reference" "R170"
			(at -2.0968 -0.173079 0)
			(unlocked yes)
			(layer "F.SilkS")
			(effects
				(font
					(size 0.762 0.762)
					(thickness 0.2032)
				)
			)
		)
		(property "Value" "DNI_49.9_1%_0402"
			(at -2.579871 11.71832 270)
			(unlocked yes)
			(layer "F.SilkS")
			(hide yes)
			(effects
				(font
					(size 0.762 0.762)
					(thickness 0.2032)
				)
			)
		)
		(sheetname "11-M2_RCB_MUX")
		(sheetfile "11-M2_RCB_MUX.kicad_sch")
		(duplicate_pad_numbers_are_jumpers no)
		(pad "1" smd rect
			(at -0.375 0 90)
			(size 0.45 0.5)
			(layers "F.Cu" "F.Mask" "F.Paste")
			(net "GPS1_PIN11")
		)
		(pad "2" smd rect
			(at 0.375 0 90)
			(size 0.45 0.5)
			(layers "F.Cu" "F.Mask" "F.Paste")
			(net "RCB_GPS1_PIN11")
		)
	)
	(footprint "Vault:RESC1005X40X25LL05T05"
		(layer "F.Cu")
		(at 210.1216 131.5162)
		(property "Reference" "R131"
			(at 4.10058 -0.216869 0)
			(unlocked yes)
			(layer "F.SilkS")
			(effects
				(font
					(size 0.762 0.762)
					(thickness 0.2032)
				)
			)
		)
		(property "Value" "DNI_0_1%_0402"
			(at -2.579871 9.56002 270)
			(unlocked yes)
			(layer "F.SilkS")
			(hide yes)
			(effects
				(font
					(size 0.762 0.762)
					(thickness 0.2032)
				)
			)
		)
		(sheetname "10-M2_GPS")
		(sheetfile "10-M2_GPS.kicad_sch")
		(duplicate_pad_numbers_are_jumpers no)
		(pad "1" smd rect
			(at -0.4 0 90)
			(size 0.45 0.45)
			(layers "F.Cu" "F.Mask" "F.Paste")
			(net "NetJ45_35")
		)
		(pad "2" smd rect
			(at 0.4 0 90)
			(size 0.45 0.45)
			(layers "F.Cu" "F.Mask" "F.Paste")
			(net "M2_GPS2_TP1")
		)
	)
	(footprint "Vault:FP-0402-L_1_0_1-W_0_5_0_1-IPC_C"
		(layer "F.Cu")
		(at 75.7216 130.9162 -90)
		(property "Reference" "C27"
			(at 0.4286 -1.373069 270)
			(unlocked yes)
			(layer "F.SilkS")
			(effects
				(font
					(size 0.762 0.762)
					(thickness 0.2286)
				)
			)
		)
		(property "Value" "0.1uF_25V_0402"
			(at 2.069035 2.567201 270)
			(unlocked yes)
			(layer "F.SilkS")
			(hide yes)
			(effects
				(font
					(size 0.762 0.762)
					(thickness 0.2286)
				)
			)
		)
		(sheetname "01-USER_IO")
		(sheetfile "01-USER_IO.kicad_sch")
		(duplicate_pad_numbers_are_jumpers no)
		(fp_line
			(start 0.65607 0.7)
			(end -0.65607 0.7)
			(stroke
				(width 0.2)
				(type solid)
			)
			(layer "F.SilkS")
		)
		(fp_line
			(start 0.65607 -0.7)
			(end -0.65607 -0.7)
			(stroke
				(width 0.2)
				(type solid)
			)
			(layer "F.SilkS")
		)
		(fp_line
			(start -0.75607 0.4)
			(end -0.75607 -0.4)
			(stroke
				(width 0.2)
				(type solid)
			)
			(layer "F.CrtYd")
		)
		(fp_line
			(start 0.75607 0.4)
			(end -0.75607 0.4)
			(stroke
				(width 0.2)
				(type solid)
			)
			(layer "F.CrtYd")
		)
		(fp_line
			(start 0.75607 0.4)
			(end 0.75607 -0.4)
			(stroke
				(width 0.2)
				(type solid)
			)
			(layer "F.CrtYd")
		)
		(fp_line
			(start 0.75607 -0.4)
			(end -0.75607 -0.4)
			(stroke
				(width 0.2)
				(type solid)
			)
			(layer "F.CrtYd")
		)
		(fp_line
			(start 0 0.5)
			(end 0 -0.5)
			(stroke
				(width 0.1)
				(type solid)
			)
			(layer "F.Fab")
		)
		(fp_line
			(start -0.75607 0.4)
			(end -0.75607 -0.4)
			(stroke
				(width 0.2)
				(type solid)
			)
			(layer "F.Fab")
		)
		(fp_line
			(start 0.75607 0.4)
			(end -0.75607 0.4)
			(stroke
				(width 0.2)
				(type solid)
			)
			(layer "F.Fab")
		)
		(fp_line
			(start 0.75607 0.4)
			(end 0.75607 -0.4)
			(stroke
				(width 0.2)
				(type solid)
			)
			(layer "F.Fab")
		)
		(fp_line
			(start 0.5 0)
			(end -0.5 0)
			(stroke
				(width 0.1)
				(type solid)
			)
			(layer "F.Fab")
		)
		(fp_line
			(start 0.75607 -0.4)
			(end -0.75607 -0.4)
			(stroke
				(width 0.2)
				(type solid)
			)
			(layer "F.Fab")
		)
		(fp_text user "${REFERENCE}"
			(at -0.00001 0.09602 270)
			(unlocked yes)
			(layer "F.Fab")
			(effects
				(font
					(face "Arial")
					(size 0.63 0.63)
					(thickness 0.1)
				)
				(justify left bottom)
			)
		)
		(pad "1" smd rect
			(at -0.36554 0 270)
			(size 0.58106 0.51213)
			(layers "F.Cu" "F.Mask" "F.Paste")
			(net "+3.3V")
			(solder_mask_margin 0)
			(solder_paste_margin 0)
		)
		(pad "2" smd rect
			(at 0.36554 0 270)
			(size 0.58106 0.51213)
			(layers "F.Cu" "F.Mask" "F.Paste")
			(net "GND")
			(solder_mask_margin 0)
			(solder_paste_margin 0)
		)
	)
	(footprint "Vault:FP-LTST-C191KGKT-MFG"
		(layer "F.Cu")
		(at 96.3216 78.5162 180)
		(property "Reference" "D4"
			(at 3.2 -0.493345 0)
			(unlocked yes)
			(layer "F.SilkS")
			(effects
				(font
					(size 0.762 0.762)
					(thickness 0.2286)
				)
				(justify left bottom)
			)
		)
		(property "Value" "LTST-C191KGKT"
			(at 18.2973 -9.341045 0)
			(unlocked yes)
			(layer "F.SilkS")
			(hide yes)
			(effects
				(font
					(size 0.762 0.762)
					(thickness 0.2286)
				)
				(justify left bottom)
			)
		)
		(sheetname "03-POWER")
		(sheetfile "03-POWER.kicad_sch")
		(duplicate_pad_numbers_are_jumpers no)
		(fp_line
			(start 0.85 0.775)
			(end -0.85 0.775)
			(stroke
				(width 0.2)
				(type solid)
			)
			(layer "F.SilkS")
		)
		(fp_line
			(start 0.85 -0.775)
			(end -0.85 -0.775)
			(stroke
				(width 0.2)
				(type solid)
			)
			(layer "F.SilkS")
		)
		(fp_circle
			(center -1.7 0)
			(end -1.7 0.125)
			(stroke
				(width 0.25)
				(type solid)
			)
			(fill no)
			(layer "F.SilkS")
		)
		(fp_line
			(start 1.25 0.55)
			(end -1.25 0.55)
			(stroke
				(width 0.2)
				(type solid)
			)
			(layer "F.CrtYd")
		)
		(fp_line
			(start 1.25 -0.55)
			(end 1.25 0.55)
			(stroke
				(width 0.2)
				(type solid)
			)
			(layer "F.CrtYd")
		)
		(fp_line
			(start 1.25 -0.55)
			(end -1.25 -0.55)
			(stroke
				(width 0.2)
				(type solid)
			)
			(layer "F.CrtYd")
		)
		(fp_line
			(start -1.25 -0.55)
			(end -1.25 0.55)
			(stroke
				(width 0.2)
				(type solid)
			)
			(layer "F.CrtYd")
		)
		(fp_line
			(start 1.25 0.55)
			(end -1.25 0.55)
			(stroke
				(width 0.2)
				(type solid)
			)
			(layer "F.Fab")
		)
		(fp_line
			(start 1.25 -0.55)
			(end 1.25 0.55)
			(stroke
				(width 0.2)
				(type solid)
			)
			(layer "F.Fab")
		)
		(fp_line
			(start 1.25 -0.55)
			(end -1.25 -0.55)
			(stroke
				(width 0.2)
				(type solid)
			)
			(layer "F.Fab")
		)
		(fp_line
			(start 0.5 0)
			(end -0.5 0)
			(stroke
				(width 0.1)
				(type solid)
			)
			(layer "F.Fab")
		)
		(fp_line
			(start 0 -0.5)
			(end 0 0.5)
			(stroke
				(width 0.1)
				(type solid)
			)
			(layer "F.Fab")
		)
		(fp_line
			(start -1.25 -0.55)
			(end -1.25 0.55)
			(stroke
				(width 0.2)
				(type solid)
			)
			(layer "F.Fab")
		)
		(fp_text user "${REFERENCE}"
			(at 0 0.29535 180)
			(unlocked yes)
			(layer "F.Fab")
			(effects
				(font
					(face "Arial")
					(size 0.63 0.63)
					(thickness 0.1)
				)
				(justify left bottom)
			)
		)
		(pad "1" smd rect
			(at -0.75 0 180)
			(size 0.8 0.8)
			(layers "F.Cu" "F.Mask" "F.Paste")
			(net "NetD4_1")
			(solder_mask_margin 0)
			(solder_paste_margin 0)
		)
		(pad "2" smd rect
			(at 0.75 0 180)
			(size 0.8 0.8)
			(layers "F.Cu" "F.Mask" "F.Paste")
			(net "+5.0V")
			(solder_mask_margin 0)
			(solder_paste_margin 0)
		)
	)
	(footprint "Vault:AMPH-901-143-6RFX_V"
		(layer "F.Cu")
		(at 69.9716 95.0786 180)
		(property "Reference" "AN1"
			(at 0.85 3.969055 0)
			(unlocked yes)
			(layer "F.SilkS")
			(effects
				(font
					(size 0.762 0.762)
					(thickness 0.2286)
				)
				(justify left bottom)
			)
		)
		(property "Value" "RF2-49B-T-00-50-G-HDW"
			(at 4.6101 -12.120245 0)
			(unlocked yes)
			(layer "F.SilkS")
			(hide yes)
			(effects
				(font
					(size 0.762 0.762)
					(thickness 0.2286)
				)
				(justify left bottom)
			)
		)
		(sheetname "01-USER_IO")
		(sheetfile "01-USER_IO.kicad_sch")
		(duplicate_pad_numbers_are_jumpers no)
		(fp_line
			(start 3.5 -1.38)
			(end 3.5 1.38)
			(stroke
				(width 0.2)
				(type solid)
			)
			(layer "F.SilkS")
		)
		(fp_line
			(start 1.38 3.5)
			(end -1.38 3.5)
			(stroke
				(width 0.2)
				(type solid)
			)
			(layer "F.SilkS")
		)
		(fp_line
			(start 1.38 -3.5)
			(end -1.38 -3.5)
			(stroke
				(width 0.2)
				(type solid)
			)
			(layer "F.SilkS")
		)
		(fp_line
			(start -3.5 -1.38)
			(end -3.5 1.38)
			(stroke
				(width 0.2)
				(type solid)
			)
			(layer "F.SilkS")
		)
		(pad "1" thru_hole rect
			(at 0 0 180)
			(size 2 2)
			(drill 1.5)
			(layers "*.Cu" "*.Mask")
			(remove_unused_layers no)
			(net "NetAN1_1")
		)
		(pad "2" thru_hole circle
			(at -2.54 -2.54 180)
			(size 2.2 2.2)
			(drill 1.7)
			(layers "*.Cu" "*.Mask")
			(remove_unused_layers no)
			(net "GND")
			(thermal_bridge_angle 90)
		)
		(pad "3" thru_hole circle
			(at -2.54 2.54 180)
			(size 2.2 2.2)
			(drill 1.7)
			(layers "*.Cu" "*.Mask")
			(remove_unused_layers no)
			(net "GND")
			(thermal_bridge_angle 90)
		)
		(pad "4" thru_hole circle
			(at 2.54 2.54 180)
			(size 2.2 2.2)
			(drill 1.7)
			(layers "*.Cu" "*.Mask")
			(remove_unused_layers no)
			(net "GND")
			(thermal_bridge_angle 90)
		)
		(pad "5" thru_hole circle
			(at 2.54 -2.54 180)
			(size 2.2 2.2)
			(drill 1.7)
			(layers "*.Cu" "*.Mask")
			(remove_unused_layers no)
			(net "GND")
			(thermal_bridge_angle 90)
		)
	)
	(footprint "Vault:FP-0402-L_1_0_1-W_0_5_0_1-IPC_C"
		(layer "F.Cu")
		(at 228.2216 132.0162)
		(property "Reference" "C89"
			(at 2.6286 0.126931 0)
			(unlocked yes)
			(layer "F.SilkS")
			(effects
				(font
					(size 0.762 0.762)
					(thickness 0.2286)
				)
			)
		)
		(property "Value" "0.1uF_25V_0402"
			(at -2.465551 9.839215 270)
			(unlocked yes)
			(layer "F.SilkS")
			(hide yes)
			(effects
				(font
					(size 0.762 0.762)
					(thickness 0.2286)
				)
			)
		)
		(sheetname "09-USBUart_PPSMUX_UARTMUX")
		(sheetfile "09-USBUart_PPSMUX_UARTMUX.kicad_sch")
		(duplicate_pad_numbers_are_jumpers no)
		(fp_line
			(start -0.65607 -0.7)
			(end 0.65607 -0.7)
			(stroke
				(width 0.2)
				(type solid)
			)
			(layer "F.SilkS")
		)
		(fp_line
			(start -0.65607 0.7)
			(end 0.65607 0.7)
			(stroke
				(width 0.2)
				(type solid)
			)
			(layer "F.SilkS")
		)
		(fp_line
			(start -0.75607 -0.4)
			(end 0.75607 -0.4)
			(stroke
				(width 0.2)
				(type solid)
			)
			(layer "F.CrtYd")
		)
		(fp_line
			(start -0.75607 0.4)
			(end -0.75607 -0.4)
			(stroke
				(width 0.2)
				(type solid)
			)
			(layer "F.CrtYd")
		)
		(fp_line
			(start -0.75607 0.4)
			(end 0.75607 0.4)
			(stroke
				(width 0.2)
				(type solid)
			)
			(layer "F.CrtYd")
		)
		(fp_line
			(start 0.75607 0.4)
			(end 0.75607 -0.4)
			(stroke
				(width 0.2)
				(type solid)
			)
			(layer "F.CrtYd")
		)
		(fp_line
			(start -0.75607 -0.4)
			(end 0.75607 -0.4)
			(stroke
				(width 0.2)
				(type solid)
			)
			(layer "F.Fab")
		)
		(fp_line
			(start -0.75607 0.4)
			(end -0.75607 -0.4)
			(stroke
				(width 0.2)
				(type solid)
			)
			(layer "F.Fab")
		)
		(fp_line
			(start -0.75607 0.4)
			(end 0.75607 0.4)
			(stroke
				(width 0.2)
				(type solid)
			)
			(layer "F.Fab")
		)
		(fp_line
			(start -0.5 0)
			(end 0.5 0)
			(stroke
				(width 0.1)
				(type solid)
			)
			(layer "F.Fab")
		)
		(fp_line
			(start 0 0.5)
			(end 0 -0.5)
			(stroke
				(width 0.1)
				(type solid)
			)
			(layer "F.Fab")
		)
		(fp_line
			(start 0.75607 0.4)
			(end 0.75607 -0.4)
			(stroke
				(width 0.2)
				(type solid)
			)
			(layer "F.Fab")
		)
		(fp_text user "${REFERENCE}"
			(at -0.00001 0.09602 360)
			(unlocked yes)
			(layer "F.Fab")
			(effects
				(font
					(face "Arial")
					(size 0.63 0.63)
					(thickness 0.1)
				)
				(justify left bottom)
			)
		)
		(pad "1" smd rect
			(at -0.36554 0)
			(size 0.58106 0.51213)
			(layers "F.Cu" "F.Mask" "F.Paste")
			(net "FTDI_VBUS")
			(solder_mask_margin 0)
			(solder_paste_margin 0)
		)
		(pad "2" smd rect
			(at 0.36554 0)
			(size 0.58106 0.51213)
			(layers "F.Cu" "F.Mask" "F.Paste")
			(net "GND")
			(solder_mask_margin 0)
			(solder_paste_margin 0)
		)
	)
)
